FILE_TYPE = CONNECTIVITY;
{Allegro Design Entry HDL 17.2-2016 S081 (4005846) 1/11/2022}
"PAGE_NUMBER" = 115;
0"NC";
1"P3V3_AUX\g";
2"P3V3_AUX\g";
3"P3V3_AUX\g";
4"P3V3_AUX\g";
5"P3V3_AUX\g";
6"P3V3_AUX\g";
7"P3V3_AUX\g";
8"P3V3_AUX\g";
9"P3V3_AUX\g";
10"P3V3_AUX\g";
11"P3V3_AUX\g";
12"P3V3_AUX\g";
13"P3V3_AUX\g";
14"P3V3_AUX\g";
15"P3V3_AUX\g";
16"P3V3_AUX\g";
17"PWRGD_FAIL_CPU1_EF_R";
18"PWRGD_FAIL_CPU1_EF_R1";
19"PWRGD_FAIL_CPU1_CD_R";
20"PWRGD_FAIL_CPU1_AB_R";
21"PWRGD_FAIL_CPU0_GH_R";
22"PWRGD_FAIL_CPU0_EF_R";
23"PWRGD_FAIL_CPU0_AB_R";
24"PWRGD_FAIL_CPU0_CD_R";
25"PWRGD_FAIL_CPU1_CD_R1";
26"PWRGD_FAIL_CPU1_AB_R1";
27"PWRGD_FAIL_CPU1_GH_R1";
28"PWRGD_FAIL_CPU1_GH_R";
29"PWRGD_FAIL_CPU0_GH_R1";
30"PWRGD_FAIL_CPU0_EF_R1";
31"PWRGD_FAIL_CPU0_CD_R1";
32"PWRGD_FAIL_CPU0_AB_R1";
33"PWRGD_FAIL_CPU0_EF";
34"PWRGD_FAIL_CPU0_CD";
35"PWRGD_FAIL_CPU1_CD";
36"PWRGD_FAIL_CPU1_GH";
37"PWRGD_FAIL_CPU1_EF";
38"PWRGD_FAIL_CPU1_AB";
39"PWRGD_FAIL_CPU0_GH";
40"PWRGD_FAIL_CPU0_AB";
%"UNIVERSAL_POWER"
"1","(1400,-2325)","0","logical_power","I10";
;
HDL_POWER"P3V3_AUX"
CDS_LIB"logical_power";
"A"11;
%"Q_RES"
"1","(1825,-2500)","0","pure_quanta","I11";
;
PART_NUMBER"CS31002FB08"
WATTAGE"1/16W"
VALUE"10K"
TOLERANCE"1%"
MATERIAL"CHIP"
PACK_TYPE"0402LF"
$LOCATION"R947"
CDS_LIB"pure_quanta"
CDS_LOCATION"R947"
$SEC"1"
CDS_SEC"1";
"B"
$PN"2"27;
"A"
$PN"1"11;
%"Q_RES"
"1","(1825,-2125)","0","pure_quanta","I12";
;
PART_NUMBER"CS21002FB06"
VALUE"1K"
WATTAGE"1/16W"
TOLERANCE"1%"
MATERIAL"CHIP"
PACK_TYPE"0402LF"
$LOCATION"R2496"
CDS_LIB"pure_quanta"
CDS_LOCATION"R2496"
$SEC"1"
CDS_SEC"1";
"B"
$PN"2"18;
"A"
$PN"1"37;
%"UNIVERSAL_POWER"
"1","(1400,-1700)","0","logical_power","I13";
;
HDL_POWER"P3V3_AUX"
CDS_LIB"logical_power";
"A"12;
%"Q_RES"
"1","(1825,-1875)","0","pure_quanta","I14";
;
PART_NUMBER"CS31002FB08"
PACK_TYPE"0402LF"
WATTAGE"1/16W"
VALUE"10K"
TOLERANCE"1%"
MATERIAL"CHIP"
$LOCATION"R946"
CDS_LIB"pure_quanta"
CDS_LOCATION"R946"
$SEC"1"
CDS_SEC"1";
"B"
$PN"2"18;
"A"
$PN"1"12;
%"UNIVERSAL_POWER"
"1","(1400,-1075)","0","logical_power","I15";
;
HDL_POWER"P3V3_AUX"
CDS_LIB"logical_power";
"A"13;
%"Q_RES"
"1","(1825,-1250)","0","pure_quanta","I16";
;
PART_NUMBER"CS31002FB08"
TOLERANCE"1%"
MATERIAL"CHIP"
PACK_TYPE"0402LF"
VALUE"10K"
WATTAGE"1/16W"
$LOCATION"R945"
CDS_LIB"pure_quanta"
CDS_LOCATION"R945"
$SEC"1"
CDS_SEC"1";
"B"
$PN"2"25;
"A"
$PN"1"13;
%"Q_RES"
"1","(1825,-1500)","0","pure_quanta","I17";
;
PART_NUMBER"CS21002FB06"
MATERIAL"CHIP"
TOLERANCE"1%"
VALUE"1K"
PACK_TYPE"0402LF"
WATTAGE"1/16W"
$LOCATION"R2495"
CDS_LIB"pure_quanta"
CDS_LOCATION"R2495"
$SEC"1"
CDS_SEC"1";
"B"
$PN"2"25;
"A"
$PN"1"35;
%"Q_RES"
"1","(1825,-875)","0","pure_quanta","I18";
;
PART_NUMBER"CS21002FB06"
PACK_TYPE"0402LF"
TOLERANCE"1%"
MATERIAL"CHIP"
VALUE"1K"
WATTAGE"1/16W"
$LOCATION"R2494"
CDS_LIB"pure_quanta"
CDS_LOCATION"R2494"
$SEC"1"
CDS_SEC"1";
"B"
$PN"2"26;
"A"
$PN"1"38;
%"Q_RES"
"1","(1825,-625)","0","pure_quanta","I19";
;
PART_NUMBER"CS31002FB08"
WATTAGE"1/16W"
PACK_TYPE"0402LF"
VALUE"10K"
TOLERANCE"1%"
MATERIAL"CHIP"
$LOCATION"R944"
CDS_LIB"pure_quanta"
CDS_LOCATION"R944"
$SEC"1"
CDS_SEC"1";
"B"
$PN"2"26;
"A"
$PN"1"14;
%"UNIVERSAL_POWER"
"1","(1400,-450)","0","logical_power","I20";
;
HDL_POWER"P3V3_AUX"
CDS_LIB"logical_power";
"A"14;
%"SCHOTTKY_12"
"1","(4100,-2500)","0","pure_quanta","I22";
;
PART_NUMBER"BC000530Z41"
PART_TYPE"SMLF"
MATERIAL"IC"
VALUE"B0530WS7F"
$LOCATION"D49"
CDS_LMAN_SYM_OUTLINE"-75,50,75,-50"
NEEDS_NO_SIZE"TRUE"
CDS_LIB"pure_quanta"
CDS_LOCATION"D49"
$SEC"1"
CDS_SEC"1";
"C"
$PN"2"1;
"A"
$PN"1"27;
%"UNIVERSAL_POWER"
"1","(4725,-2325)","0","logical_power","I24";
;
HDL_POWER"P3V3_AUX"
CDS_LIB"logical_power";
"A"1;
%"SCHOTTKY_12"
"1","(4100,-1875)","0","pure_quanta","I25";
;
PART_NUMBER"BC000530Z41"
PART_TYPE"SMLF"
MATERIAL"IC"
VALUE"B0530WS7F"
$LOCATION"D48"
CDS_LIB"pure_quanta"
NEEDS_NO_SIZE"TRUE"
CDS_LMAN_SYM_OUTLINE"-75,50,75,-50"
CDS_LOCATION"D48"
$SEC"1"
CDS_SEC"1";
"C"
$PN"2"7;
"A"
$PN"1"18;
%"SCHOTTKY_12"
"1","(4100,-1250)","0","pure_quanta","I27";
;
PART_NUMBER"BC000530Z41"
VALUE"B0530WS7F"
PART_TYPE"SMLF"
MATERIAL"IC"
$LOCATION"D47"
CDS_LMAN_SYM_OUTLINE"-75,50,75,-50"
NEEDS_NO_SIZE"TRUE"
CDS_LIB"pure_quanta"
CDS_LOCATION"D47"
$SEC"1"
CDS_SEC"1";
"C"
$PN"2"2;
"A"
$PN"1"25;
%"SCHOTTKY_12"
"1","(4100,-625)","0","pure_quanta","I29";
;
PART_NUMBER"BC000530Z41"
PART_TYPE"SMLF"
VALUE"B0530WS7F"
MATERIAL"IC"
$LOCATION"D46"
CDS_LIB"pure_quanta"
NEEDS_NO_SIZE"TRUE"
CDS_LMAN_SYM_OUTLINE"-75,50,75,-50"
CDS_LOCATION"D46"
$SEC"1"
CDS_SEC"1";
"C"
$PN"2"3;
"A"
$PN"1"26;
%"UNIVERSAL_POWER"
"1","(4725,-1700)","0","logical_power","I30";
;
HDL_POWER"P3V3_AUX"
CDS_LIB"logical_power";
"A"7;
%"UNIVERSAL_POWER"
"1","(4725,-1075)","0","logical_power","I31";
;
HDL_POWER"P3V3_AUX"
CDS_LIB"logical_power";
"A"2;
%"UNIVERSAL_POWER"
"1","(4725,-450)","0","logical_power","I32";
;
HDL_POWER"P3V3_AUX"
CDS_LIB"logical_power";
"A"3;
%"Q_RES"
"1","(1825,350)","0","pure_quanta","I37";
;
PART_NUMBER"CS31002FB08"
WATTAGE"1/16W"
PACK_TYPE"0402LF"
VALUE"10K"
TOLERANCE"1%"
MATERIAL"CHIP"
$LOCATION"R943"
CDS_LIB"pure_quanta"
CDS_LOCATION"R943"
$SEC"1"
CDS_SEC"1";
"B"
$PN"2"29;
"A"
$PN"1"8;
%"Q_RES"
"1","(1825,100)","0","pure_quanta","I38";
;
PART_NUMBER"CS21002FB06"
PACK_TYPE"0402LF"
WATTAGE"1/16W"
VALUE"1K"
TOLERANCE"1%"
MATERIAL"CHIP"
$LOCATION"R2493"
CDS_LIB"pure_quanta"
CDS_LOCATION"R2493"
$SEC"1"
CDS_SEC"1";
"B"
$PN"2"29;
"A"
$PN"1"39;
%"UNIVERSAL_POWER"
"1","(1400,525)","0","logical_power","I39";
;
HDL_POWER"P3V3_AUX"
CDS_LIB"logical_power";
"A"8;
%"Q_RES"
"1","(1825,975)","0","pure_quanta","I40";
;
PART_NUMBER"CS31002FB08"
TOLERANCE"1%"
WATTAGE"1/16W"
PACK_TYPE"0402LF"
MATERIAL"CHIP"
VALUE"10K"
$LOCATION"R942"
CDS_LIB"pure_quanta"
CDS_LOCATION"R942"
$SEC"1"
CDS_SEC"1";
"B"
$PN"2"30;
"A"
$PN"1"15;
%"Q_RES"
"1","(1825,725)","0","pure_quanta","I41";
;
PART_NUMBER"CS21002FB06"
WATTAGE"1/16W"
PACK_TYPE"0402LF"
TOLERANCE"1%"
VALUE"1K"
MATERIAL"CHIP"
$LOCATION"R2492"
CDS_LIB"pure_quanta"
CDS_LOCATION"R2492"
$SEC"1"
CDS_SEC"1";
"B"
$PN"2"30;
"A"
$PN"1"33;
%"Q_RES"
"1","(1825,1350)","0","pure_quanta","I42";
;
PART_NUMBER"CS21002FB06"
VALUE"1K"
TOLERANCE"1%"
PACK_TYPE"0402LF"
WATTAGE"1/16W"
MATERIAL"CHIP"
$LOCATION"R2491"
CDS_LIB"pure_quanta"
CDS_LOCATION"R2491"
$SEC"1"
CDS_SEC"1";
"B"
$PN"2"31;
"A"
$PN"1"34;
%"UNIVERSAL_POWER"
"1","(1400,1150)","0","logical_power","I43";
;
HDL_POWER"P3V3_AUX"
CDS_LIB"logical_power";
"A"15;
%"UNIVERSAL_POWER"
"1","(1400,1775)","0","logical_power","I44";
;
HDL_POWER"P3V3_AUX"
CDS_LIB"logical_power";
"A"9;
%"Q_RES"
"1","(1825,1600)","0","pure_quanta","I45";
;
PART_NUMBER"CS31002FB08"
VALUE"10K"
TOLERANCE"1%"
MATERIAL"CHIP"
WATTAGE"1/16W"
PACK_TYPE"0402LF"
$LOCATION"R941"
CDS_LIB"pure_quanta"
CDS_LOCATION"R941"
$SEC"1"
CDS_SEC"1";
"B"
$PN"2"31;
"A"
$PN"1"9;
%"Q_RES"
"1","(1825,1975)","0","pure_quanta","I46";
;
PART_NUMBER"CS21002FB06"
WATTAGE"1/16W"
MATERIAL"CHIP"
VALUE"1K"
TOLERANCE"1%"
PACK_TYPE"0402LF"
$LOCATION"R2490"
CDS_LIB"pure_quanta"
CDS_LOCATION"R2490"
$SEC"1"
CDS_SEC"1";
"B"
$PN"2"32;
"A"
$PN"1"40;
%"UNIVERSAL_POWER"
"1","(1400,2400)","0","logical_power","I47";
;
HDL_POWER"P3V3_AUX"
CDS_LIB"logical_power";
"A"16;
%"Q_RES"
"1","(1825,2225)","0","pure_quanta","I48";
;
PART_NUMBER"CS31002FB08"
VALUE"10K"
TOLERANCE"1%"
PACK_TYPE"0402LF"
WATTAGE"1/16W"
MATERIAL"CHIP"
$LOCATION"R940"
CDS_LIB"pure_quanta"
CDS_LOCATION"R940"
$SEC"1"
CDS_SEC"1";
"B"
$PN"2"32;
"A"
$PN"1"16;
%"SCHOTTKY_12"
"1","(4100,350)","0","pure_quanta","I50";
;
PART_NUMBER"BC000530Z41"
VALUE"B0530WS7F"
PART_TYPE"SMLF"
MATERIAL"IC"
$LOCATION"D45"
CDS_LIB"pure_quanta"
NEEDS_NO_SIZE"TRUE"
CDS_LMAN_SYM_OUTLINE"-75,50,75,-50"
CDS_LOCATION"D45"
$SEC"1"
CDS_SEC"1";
"C"
$PN"2"5;
"A"
$PN"1"29;
%"SCHOTTKY_12"
"1","(4100,975)","0","pure_quanta","I52";
;
PART_NUMBER"BC000530Z41"
PART_TYPE"SMLF"
VALUE"B0530WS7F"
MATERIAL"IC"
$LOCATION"D44"
CDS_LMAN_SYM_OUTLINE"-75,50,75,-50"
NEEDS_NO_SIZE"TRUE"
CDS_LIB"pure_quanta"
CDS_LOCATION"D44"
$SEC"1"
CDS_SEC"1";
"C"
$PN"2"6;
"A"
$PN"1"30;
%"SCHOTTKY_12"
"1","(4100,1600)","0","pure_quanta","I54";
;
PART_NUMBER"BC000530Z41"
VALUE"B0530WS7F"
PART_TYPE"SMLF"
MATERIAL"IC"
$LOCATION"D43"
CDS_LIB"pure_quanta"
NEEDS_NO_SIZE"TRUE"
CDS_LMAN_SYM_OUTLINE"-75,50,75,-50"
CDS_LOCATION"D43"
$SEC"1"
CDS_SEC"1";
"C"
$PN"2"4;
"A"
$PN"1"31;
%"UNIVERSAL_POWER"
"1","(4725,525)","0","logical_power","I56";
;
HDL_POWER"P3V3_AUX"
CDS_LIB"logical_power";
"A"5;
%"UNIVERSAL_POWER"
"1","(4725,1150)","0","logical_power","I57";
;
HDL_POWER"P3V3_AUX"
CDS_LIB"logical_power";
"A"6;
%"UNIVERSAL_POWER"
"1","(4725,1775)","0","logical_power","I58";
;
HDL_POWER"P3V3_AUX"
CDS_LIB"logical_power";
"A"4;
%"SCHOTTKY_12"
"1","(4100,2225)","0","pure_quanta","I59";
;
PART_NUMBER"BC000530Z41"
PART_TYPE"SMLF"
VALUE"B0530WS7F"
MATERIAL"IC"
$LOCATION"D42"
CDS_LMAN_SYM_OUTLINE"-75,50,75,-50"
NEEDS_NO_SIZE"TRUE"
CDS_LIB"pure_quanta"
CDS_LOCATION"D42"
$SEC"1"
CDS_SEC"1";
"C"
$PN"2"10;
"A"
$PN"1"32;
%"UNIVERSAL_POWER"
"1","(4725,2400)","0","logical_power","I60";
;
HDL_POWER"P3V3_AUX"
CDS_LIB"logical_power";
"A"10;
%"Q_RES"
"1","(4075,-2750)","0","pure_quanta","I65";
;
PART_NUMBER"CS03322FB03"
TOLERANCE"1%"
VALUE"33.2"
LOCATION"R2505"
CDS_LIB"pure_quanta"
MATERIAL"CHIP"
PACK_TYPE"0402LF"
WATTAGE"1/16W"
$SEC"1"
CDS_SEC"1";
"B"
$PN"2"28;
"A"
$PN"1"27;
%"Q_RES"
"1","(4075,-2125)","0","pure_quanta","I66";
;
PART_NUMBER"CS03322FB03"
TOLERANCE"1%"
VALUE"33.2"
LOCATION"R2504"
CDS_LIB"pure_quanta"
MATERIAL"CHIP"
PACK_TYPE"0402LF"
WATTAGE"1/16W"
$SEC"1"
CDS_SEC"1";
"B"
$PN"2"17;
"A"
$PN"1"18;
%"Q_RES"
"1","(4075,-1500)","0","pure_quanta","I67";
;
PART_NUMBER"CS03322FB03"
TOLERANCE"1%"
VALUE"33.2"
LOCATION"R2503"
CDS_LIB"pure_quanta"
MATERIAL"CHIP"
PACK_TYPE"0402LF"
WATTAGE"1/16W"
$SEC"1"
CDS_SEC"1";
"B"
$PN"2"19;
"A"
$PN"1"25;
%"Q_RES"
"1","(4075,-875)","0","pure_quanta","I68";
;
PART_NUMBER"CS03322FB03"
VALUE"33.2"
TOLERANCE"1%"
LOCATION"R2502"
WATTAGE"1/16W"
PACK_TYPE"0402LF"
MATERIAL"CHIP"
CDS_LIB"pure_quanta"
$SEC"1"
CDS_SEC"1";
"B"
$PN"2"20;
"A"
$PN"1"26;
%"Q_RES"
"1","(4075,100)","0","pure_quanta","I69";
;
PART_NUMBER"CS03322FB03"
VALUE"33.2"
TOLERANCE"1%"
LOCATION"R2501"
WATTAGE"1/16W"
PACK_TYPE"0402LF"
MATERIAL"CHIP"
CDS_LIB"pure_quanta"
$SEC"1"
CDS_SEC"1";
"B"
$PN"2"21;
"A"
$PN"1"29;
%"Q_RES"
"1","(4075,725)","0","pure_quanta","I70";
;
PART_NUMBER"CS03322FB03"
VALUE"33.2"
TOLERANCE"1%"
LOCATION"R2500"
WATTAGE"1/16W"
PACK_TYPE"0402LF"
MATERIAL"CHIP"
CDS_LIB"pure_quanta"
$SEC"1"
CDS_SEC"1";
"B"
$PN"2"22;
"A"
$PN"1"30;
%"Q_RES"
"1","(4075,1350)","0","pure_quanta","I71";
;
PART_NUMBER"CS03322FB03"
VALUE"33.2"
TOLERANCE"1%"
LOCATION"R2499"
WATTAGE"1/16W"
PACK_TYPE"0402LF"
MATERIAL"CHIP"
CDS_LIB"pure_quanta"
$SEC"1"
CDS_SEC"1";
"B"
$PN"2"24;
"A"
$PN"1"31;
%"Q_RES"
"1","(4075,1975)","0","pure_quanta","I72";
;
PART_NUMBER"CS03322FB03"
VALUE"33.2"
TOLERANCE"1%"
LOCATION"R2498"
CDS_LIB"pure_quanta"
MATERIAL"CHIP"
PACK_TYPE"0402LF"
WATTAGE"1/16W"
$SEC"1"
CDS_SEC"1";
"B"
$PN"2"23;
"A"
$PN"1"32;
%"Q_RES"
"1","(1825,-2750)","0","pure_quanta","I9";
;
PART_NUMBER"CS21002FB06"
WATTAGE"1/16W"
MATERIAL"CHIP"
PACK_TYPE"0402LF"
VALUE"1K"
TOLERANCE"1%"
$LOCATION"R2497"
CDS_LIB"pure_quanta"
CDS_LOCATION"R2497"
$SEC"1"
CDS_SEC"1";
"B"
$PN"2"27;
"A"
$PN"1"36;
END.
